(kicad_pcb
	(version 20260206)
	(generator "pcbnew")
	(generator_version "10.0")
	(general
		(thickness 1.6)
		(legacy_teardrops no)
	)
	(paper "A4")
	(title_block
		(title "9052_F0T_PDB_Converter_Brick_F_V03_1208_1600_OCP.brd")
		(comment 1 "Grand Teton / footprints 314-318 of 578")
	)
	(layers
		(0 "F.Cu" signal "TOP")
		(4 "In1.Cu" signal "GND")
		(6 "In2.Cu" signal "IN1")
		(8 "In3.Cu" signal "GND1")
		(10 "In4.Cu" signal "VCC")
		(12 "In5.Cu" signal "VCC1")
		(14 "In6.Cu" signal "GND2")
		(16 "In7.Cu" signal "IN2")
		(18 "In8.Cu" signal "GND3")
		(2 "B.Cu" signal "BOTTOM")
		(9 "F.Adhes" user "F.Adhesive")
		(11 "B.Adhes" user "B.Adhesive")
		(13 "F.Paste" user "Package Geometry/Pastemask Top")
		(15 "B.Paste" user "Package Geometry/Pastemask Bottom")
		(5 "F.SilkS" user "Ref Des/Silkscreen Top")
		(7 "B.SilkS" user "Ref Des/Silkscreen Bottom")
		(1 "F.Mask" user "Board Geometry/Soldermask Top")
		(3 "B.Mask" user "Board Geometry/Soldermask Bottom")
		(17 "Dwgs.User" user "User.Drawings")
		(19 "Cmts.User" user "User.Comments")
		(21 "Eco1.User" user "User.Eco1")
		(23 "Eco2.User" user "User.Eco2")
		(25 "Edge.Cuts" user "Board Geometry/Outline")
		(27 "Margin" user)
		(31 "F.CrtYd" user "Package Geometry/Place Bound Top")
		(29 "B.CrtYd" user "Package Geometry/Place Bound Bottom")
		(35 "F.Fab" user "Ref Des/Assembly Top")
		(33 "B.Fab" user "Ref Des/Assembly Bottom")
	)
	(footprint ""
		(layer "B.Cu")
		(at 195.961 -88.392)
		(property "Reference" "U25"
			(at 4.699 -4.67233 0)
			(unlocked yes)
			(layer "B.SilkS")
			(effects
				(font
					(size 0.7874 0.5842)
					(thickness 0.1524)
				)
				(justify left mirror)
			)
		)
		(property "Value" ""
			(at 0 0 0)
			(layer "B.Fab")
			(effects
				(font
					(size 1.27 1.27)
				)
				(justify mirror)
			)
		)
		(duplicate_pad_numbers_are_jumpers no)
		(fp_line
			(start -2.161032 -3.299968)
			(end -2.161032 3.299968)
			(stroke
				(width 0.1524)
				(type default)
			)
			(layer "B.SilkS")
		)
		(fp_line
			(start -2.161032 3.299968)
			(end 2.161032 3.299968)
			(stroke
				(width 0.1524)
				(type default)
			)
			(layer "B.SilkS")
		)
		(fp_line
			(start -1.013968 -3.299968)
			(end -2.161032 -3.299968)
			(stroke
				(width 0.1524)
				(type default)
			)
			(layer "B.SilkS")
		)
		(fp_line
			(start 0 -2.54)
			(end -1.013968 -3.299968)
			(stroke
				(width 0.1524)
				(type default)
			)
			(layer "B.SilkS")
		)
		(fp_line
			(start 1.013968 -3.299968)
			(end 0 -2.54)
			(stroke
				(width 0.1524)
				(type default)
			)
			(layer "B.SilkS")
		)
		(fp_line
			(start 2.161032 -3.299968)
			(end 1.013968 -3.299968)
			(stroke
				(width 0.1524)
				(type default)
			)
			(layer "B.SilkS")
		)
		(fp_line
			(start 2.161032 3.299968)
			(end 2.161032 -3.299968)
			(stroke
				(width 0.1524)
				(type default)
			)
			(layer "B.SilkS")
		)
		(fp_poly
			(pts
				(xy 4.572 -3.433064) (xy 4.572 -2.417064) (xy 3.556 -2.925064)
			)
			(stroke
				(width 0)
				(type default)
			)
			(fill yes)
			(layer "B.SilkS")
		)
		(fp_line
			(start -2.249932 -3.299968)
			(end 2.249932 -3.299968)
			(stroke
				(width 0.1)
				(type default)
			)
			(layer "B.Fab")
		)
		(fp_line
			(start -2.249932 3.299968)
			(end -2.249932 -3.299968)
			(stroke
				(width 0.1)
				(type default)
			)
			(layer "B.Fab")
		)
		(fp_line
			(start 2.249932 -3.299968)
			(end 2.249932 3.299968)
			(stroke
				(width 0.1)
				(type default)
			)
			(layer "B.Fab")
		)
		(fp_line
			(start 2.249932 3.299968)
			(end -2.249932 3.299968)
			(stroke
				(width 0.1)
				(type default)
			)
			(layer "B.Fab")
		)
		(fp_poly
			(pts
				(xy 4.572 -3.433064) (xy 4.572 -2.417064) (xy 3.556 -2.925064)
			)
			(stroke
				(width 0)
				(type default)
			)
			(fill yes)
			(layer "B.Fab")
		)
		(pad "1" smd rect
			(at 2.84988 -2.925064 270)
			(size 0.4064 1.1176)
			(layers "B.Cu" "B.Mask" "B.Paste")
			(net "PCA9543_MISC_A0")
		)
		(pad "2" smd rect
			(at 2.84988 -2.275078 270)
			(size 0.4064 1.1176)
			(layers "B.Cu" "B.Mask" "B.Paste")
			(net "PCA9543_MISC_A1")
		)
		(pad "3" smd rect
			(at 2.84988 -1.625092 270)
			(size 0.4064 1.1176)
			(layers "B.Cu" "B.Mask" "B.Paste")
			(net "RST_SMB_PDB_BUF_R1_N")
		)
		(pad "4" smd rect
			(at 2.84988 -0.975106 270)
			(size 0.4064 1.1176)
			(layers "B.Cu" "B.Mask" "B.Paste")
			(net "PU_9543_0_INT0")
		)
		(pad "5" smd rect
			(at 2.84988 -0.32512 270)
			(size 0.4064 1.1176)
			(layers "B.Cu" "B.Mask" "B.Paste")
			(net "SMB_VPDB_MISC_SDA")
		)
		(pad "6" smd rect
			(at 2.84988 0.32512 270)
			(size 0.4064 1.1176)
			(layers "B.Cu" "B.Mask" "B.Paste")
			(net "SMB_VPDB_MISC_SCL")
		)
		(pad "7" smd rect
			(at 2.84988 0.975106 270)
			(size 0.4064 1.1176)
			(layers "B.Cu" "B.Mask" "B.Paste")
			(net "PU_9543_0_INT1")
		)
		(pad "8" smd rect
			(at 2.84988 1.625092 270)
			(size 0.4064 1.1176)
			(layers "B.Cu" "B.Mask" "B.Paste")
			(net "SMB_HPDB_MISC_SDA")
		)
		(pad "9" smd rect
			(at 2.84988 2.275078 270)
			(size 0.4064 1.1176)
			(layers "B.Cu" "B.Mask" "B.Paste")
			(net "SMB_HPDB_MISC_SCL")
		)
		(pad "10" smd rect
			(at 2.84988 2.925064 270)
			(size 0.4064 1.1176)
			(layers "B.Cu" "B.Mask" "B.Paste")
			(net "GND")
		)
		(pad "11" smd rect
			(at -2.84988 2.925064 270)
			(size 0.4064 1.1176)
			(layers "B.Cu" "B.Mask" "B.Paste")
			(net "PU_9543_1_INT0")
		)
		(pad "12" smd rect
			(at -2.84988 2.275078 270)
			(size 0.4064 1.1176)
			(layers "B.Cu" "B.Mask" "B.Paste")
			(net "SMB_P52V_VPDB_SDA")
		)
		(pad "13" smd rect
			(at -2.84988 1.625092 270)
			(size 0.4064 1.1176)
			(layers "B.Cu" "B.Mask" "B.Paste")
			(net "SMB_P52V_VPDB_SCL_R")
		)
		(pad "14" smd rect
			(at -2.84988 0.975106 270)
			(size 0.4064 1.1176)
			(layers "B.Cu" "B.Mask" "B.Paste")
			(net "PU_9543_1_INT1")
		)
		(pad "15" smd rect
			(at -2.84988 0.32512 270)
			(size 0.4064 1.1176)
			(layers "B.Cu" "B.Mask" "B.Paste")
			(net "SMB_P52V_HPDB_SDA")
		)
		(pad "16" smd rect
			(at -2.84988 -0.32512 270)
			(size 0.4064 1.1176)
			(layers "B.Cu" "B.Mask" "B.Paste")
			(net "SMB_P52V_HPDB_SCL")
		)
		(pad "17" smd rect
			(at -2.84988 -0.975106 270)
			(size 0.4064 1.1176)
			(layers "B.Cu" "B.Mask" "B.Paste")
			(net "TP_9543_MISC_INT_N")
		)
		(pad "18" smd rect
			(at -2.84988 -1.625092 270)
			(size 0.4064 1.1176)
			(layers "B.Cu" "B.Mask" "B.Paste")
			(net "SMB_PDB_MISC_SCL")
		)
		(pad "19" smd rect
			(at -2.84988 -2.275078 270)
			(size 0.4064 1.1176)
			(layers "B.Cu" "B.Mask" "B.Paste")
			(net "SMB_PDB_MISC_SDA")
		)
		(pad "20" smd rect
			(at -2.84988 -2.925064 270)
			(size 0.4064 1.1176)
			(layers "B.Cu" "B.Mask" "B.Paste")
			(net "P3V3_AUX")
		)
	)
	(footprint ""
		(layer "B.Cu")
		(at 289.38093 -38.032436 180)
		(property "Reference" "D6"
			(at -2.0828 1.28143 0)
			(unlocked yes)
			(layer "B.SilkS")
			(effects
				(font
					(size 0.7874 0.5842)
					(thickness 0.1524)
				)
				(justify left mirror)
			)
		)
		(property "Value" ""
			(at 0 0 0)
			(layer "B.Fab")
			(effects
				(font
					(size 1.27 1.27)
				)
				(justify mirror)
			)
		)
		(duplicate_pad_numbers_are_jumpers no)
		(fp_line
			(start 2.050796 0.700024)
			(end 2.050796 -0.700024)
			(stroke
				(width 0.1524)
				(type default)
			)
			(layer "B.SilkS")
		)
		(fp_line
			(start 2.050796 -0.700024)
			(end -2.050796 -0.700024)
			(stroke
				(width 0.1524)
				(type default)
			)
			(layer "B.SilkS")
		)
		(fp_line
			(start 0.30607 0.500126)
			(end -0.193802 0)
			(stroke
				(width 0.1524)
				(type default)
			)
			(layer "B.SilkS")
		)
		(fp_line
			(start 0.30607 -0.500126)
			(end 0.30607 0.500126)
			(stroke
				(width 0.1524)
				(type default)
			)
			(layer "B.SilkS")
		)
		(fp_line
			(start -0.193802 0)
			(end 0.30607 -0.500126)
			(stroke
				(width 0.1524)
				(type default)
			)
			(layer "B.SilkS")
		)
		(fp_line
			(start -0.293878 -0.500126)
			(end -0.293878 0.500126)
			(stroke
				(width 0.1524)
				(type default)
			)
			(layer "B.SilkS")
		)
		(fp_line
			(start -2.050796 0.700024)
			(end 2.050796 0.700024)
			(stroke
				(width 0.1524)
				(type default)
			)
			(layer "B.SilkS")
		)
		(fp_line
			(start -2.050796 -0.700024)
			(end -2.050796 0.700024)
			(stroke
				(width 0.1524)
				(type default)
			)
			(layer "B.SilkS")
		)
		(fp_line
			(start -2.051304 0.6985)
			(end -2.051304 0.635)
			(stroke
				(width 0.1524)
				(type default)
			)
			(layer "B.SilkS")
		)
		(fp_line
			(start -2.051304 0.635)
			(end -2.152904 0.635)
			(stroke
				(width 0.1524)
				(type default)
			)
			(layer "B.SilkS")
		)
		(fp_line
			(start -2.064004 -0.6731)
			(end -2.064004 -0.6985)
			(stroke
				(width 0.1524)
				(type default)
			)
			(layer "B.SilkS")
		)
		(fp_line
			(start -2.064004 -0.6985)
			(end -2.229104 -0.6985)
			(stroke
				(width 0.1524)
				(type default)
			)
			(layer "B.SilkS")
		)
		(fp_line
			(start -2.152904 0.635)
			(end -2.152904 -0.6985)
			(stroke
				(width 0.1524)
				(type default)
			)
			(layer "B.SilkS")
		)
		(fp_line
			(start -2.152904 -0.6985)
			(end -2.343404 -0.6985)
			(stroke
				(width 0.1524)
				(type default)
			)
			(layer "B.SilkS")
		)
		(fp_line
			(start -2.229104 0.6985)
			(end -2.051304 0.6985)
			(stroke
				(width 0.1524)
				(type default)
			)
			(layer "B.SilkS")
		)
		(fp_line
			(start -2.229104 -0.6985)
			(end -2.229104 0.6985)
			(stroke
				(width 0.1524)
				(type default)
			)
			(layer "B.SilkS")
		)
		(fp_line
			(start -2.343404 0.6985)
			(end -2.216404 0.6985)
			(stroke
				(width 0.1524)
				(type default)
			)
			(layer "B.SilkS")
		)
		(fp_line
			(start -2.343404 -0.6985)
			(end -2.343404 0.6985)
			(stroke
				(width 0.1524)
				(type default)
			)
			(layer "B.SilkS")
		)
		(fp_line
			(start 0.899922 0.700024)
			(end 0.899922 -0.700024)
			(stroke
				(width 0.1)
				(type default)
			)
			(layer "B.Fab")
		)
		(fp_line
			(start 0.899922 -0.700024)
			(end -0.899922 -0.700024)
			(stroke
				(width 0.1)
				(type default)
			)
			(layer "B.Fab")
		)
		(fp_line
			(start -0.899922 0.700024)
			(end 0.899922 0.700024)
			(stroke
				(width 0.1)
				(type default)
			)
			(layer "B.Fab")
		)
		(fp_line
			(start -0.899922 -0.700024)
			(end -0.899922 0.700024)
			(stroke
				(width 0.1)
				(type default)
			)
			(layer "B.Fab")
		)
		(fp_text user "+"
			(at 3.05435 1.2446 90)
			(unlocked yes)
			(layer "B.SilkS")
			(effects
				(font
					(size 1.905 1.4224)
					(thickness 0.1524)
				)
				(justify left mirror)
			)
		)
		(fp_text user "-"
			(at -3.880104 0.23495 0)
			(unlocked yes)
			(layer "B.SilkS")
			(effects
				(font
					(size 1.905 1.4224)
					(thickness 0.1524)
				)
				(justify left mirror)
			)
		)
		(fp_text user "+"
			(at 3.123946 0.762 90)
			(unlocked yes)
			(layer "B.Fab")
			(effects
				(font
					(size 1.905 1.4224)
					(thickness 0.1524)
				)
				(justify left mirror)
			)
		)
		(fp_text user "-"
			(at -3.880104 0.23495 0)
			(unlocked yes)
			(layer "B.Fab")
			(effects
				(font
					(size 1.905 1.4224)
					(thickness 0.1524)
				)
				(justify left mirror)
			)
		)
		(pad "1" smd rect
			(at 1.199896 0 90)
			(size 0.6604 1.3716)
			(layers "B.Cu" "B.Mask" "B.Paste")
			(net "FM_AC_PWR_CYCLE_N")
		)
		(pad "2" smd rect
			(at -1.199896 0 270)
			(size 0.6604 1.3716)
			(layers "B.Cu" "B.Mask" "B.Paste")
			(net "FM_AC_PWR_CYCLE_R1_N")
		)
	)
	(footprint ""
		(layer "B.Cu")
		(at 104.652826 -114.046 -90)
		(property "Reference" "R202"
			(at 0 0 90)
			(layer "B.SilkS")
			(hide yes)
			(effects
				(font
					(size 1.27 1.27)
				)
				(justify mirror)
			)
		)
		(property "Value" ""
			(at 0 0 90)
			(layer "B.Fab")
			(effects
				(font
					(size 1.27 1.27)
				)
				(justify mirror)
			)
		)
		(duplicate_pad_numbers_are_jumpers no)
		(fp_line
			(start -0.7874 0.4064)
			(end 0.7874 0.4064)
			(stroke
				(width 0.1524)
				(type default)
			)
			(layer "B.SilkS")
		)
		(fp_line
			(start 0.7874 0.4064)
			(end 0.7874 -0.4064)
			(stroke
				(width 0.1524)
				(type default)
			)
			(layer "B.SilkS")
		)
		(fp_line
			(start -0.7874 -0.4064)
			(end -0.7874 0.4064)
			(stroke
				(width 0.1524)
				(type default)
			)
			(layer "B.SilkS")
		)
		(fp_line
			(start 0.7874 -0.4064)
			(end -0.7874 -0.4064)
			(stroke
				(width 0.1524)
				(type default)
			)
			(layer "B.SilkS")
		)
		(fp_line
			(start -0.67945 0.3048)
			(end -0.120396 0.3048)
			(stroke
				(width 0.1)
				(type default)
			)
			(layer "B.Fab")
		)
		(fp_line
			(start -0.120396 0.3048)
			(end -0.120396 0.2794)
			(stroke
				(width 0.1)
				(type default)
			)
			(layer "B.Fab")
		)
		(fp_line
			(start 0.12065 0.3048)
			(end 0.67945 0.3048)
			(stroke
				(width 0.1)
				(type default)
			)
			(layer "B.Fab")
		)
		(fp_line
			(start 0.67945 0.3048)
			(end 0.67945 -0.305054)
			(stroke
				(width 0.1)
				(type default)
			)
			(layer "B.Fab")
		)
		(fp_line
			(start -0.120396 0.2794)
			(end 0.12065 0.2794)
			(stroke
				(width 0.1)
				(type default)
			)
			(layer "B.Fab")
		)
		(fp_line
			(start 0.12065 0.2794)
			(end 0.12065 0.3048)
			(stroke
				(width 0.1)
				(type default)
			)
			(layer "B.Fab")
		)
		(fp_line
			(start -0.12065 -0.2794)
			(end -0.12065 -0.3048)
			(stroke
				(width 0.1)
				(type default)
			)
			(layer "B.Fab")
		)
		(fp_line
			(start 0.12065 -0.2794)
			(end -0.12065 -0.2794)
			(stroke
				(width 0.1)
				(type default)
			)
			(layer "B.Fab")
		)
		(fp_line
			(start -0.67945 -0.3048)
			(end -0.67945 0.3048)
			(stroke
				(width 0.1)
				(type default)
			)
			(layer "B.Fab")
		)
		(fp_line
			(start -0.12065 -0.3048)
			(end -0.67945 -0.3048)
			(stroke
				(width 0.1)
				(type default)
			)
			(layer "B.Fab")
		)
		(fp_line
			(start 0.12065 -0.305054)
			(end 0.12065 -0.2794)
			(stroke
				(width 0.1)
				(type default)
			)
			(layer "B.Fab")
		)
		(fp_line
			(start 0.67945 -0.305054)
			(end 0.12065 -0.305054)
			(stroke
				(width 0.1)
				(type default)
			)
			(layer "B.Fab")
		)
		(pad "1" smd circle
			(at 0.40005 0 90)
			(size 0 0)
			(layers "B.Cu" "B.Mask" "B.Paste")
			(net "BRICK_P12V_EN_R_N")
		)
		(pad "2" smd circle
			(at -0.40005 0 90)
			(size 0 0)
			(layers "B.Cu" "B.Mask" "B.Paste")
			(net "BRICK_P12V_1_EN_N")
		)
	)
	(footprint ""
		(layer "B.Cu")
		(at 180.850286 -76.708 90)
		(property "Reference" "PR320"
			(at 0 0 90)
			(layer "B.SilkS")
			(hide yes)
			(effects
				(font
					(size 1.27 1.27)
				)
				(justify mirror)
			)
		)
		(property "Value" ""
			(at 0 0 90)
			(layer "B.Fab")
			(effects
				(font
					(size 1.27 1.27)
				)
				(justify mirror)
			)
		)
		(duplicate_pad_numbers_are_jumpers no)
		(fp_line
			(start 0.7874 -0.4064)
			(end -0.7874 -0.4064)
			(stroke
				(width 0.1524)
				(type default)
			)
			(layer "B.SilkS")
		)
		(fp_line
			(start -0.7874 -0.4064)
			(end -0.7874 0.4064)
			(stroke
				(width 0.1524)
				(type default)
			)
			(layer "B.SilkS")
		)
		(fp_line
			(start 0.7874 0.4064)
			(end 0.7874 -0.4064)
			(stroke
				(width 0.1524)
				(type default)
			)
			(layer "B.SilkS")
		)
		(fp_line
			(start -0.7874 0.4064)
			(end 0.7874 0.4064)
			(stroke
				(width 0.1524)
				(type default)
			)
			(layer "B.SilkS")
		)
		(fp_line
			(start 0.67945 -0.305054)
			(end 0.12065 -0.305054)
			(stroke
				(width 0.1)
				(type default)
			)
			(layer "B.Fab")
		)
		(fp_line
			(start 0.12065 -0.305054)
			(end 0.12065 -0.2794)
			(stroke
				(width 0.1)
				(type default)
			)
			(layer "B.Fab")
		)
		(fp_line
			(start -0.12065 -0.3048)
			(end -0.67945 -0.3048)
			(stroke
				(width 0.1)
				(type default)
			)
			(layer "B.Fab")
		)
		(fp_line
			(start -0.67945 -0.3048)
			(end -0.67945 0.3048)
			(stroke
				(width 0.1)
				(type default)
			)
			(layer "B.Fab")
		)
		(fp_line
			(start 0.12065 -0.2794)
			(end -0.12065 -0.2794)
			(stroke
				(width 0.1)
				(type default)
			)
			(layer "B.Fab")
		)
		(fp_line
			(start -0.12065 -0.2794)
			(end -0.12065 -0.3048)
			(stroke
				(width 0.1)
				(type default)
			)
			(layer "B.Fab")
		)
		(fp_line
			(start 0.12065 0.2794)
			(end 0.12065 0.3048)
			(stroke
				(width 0.1)
				(type default)
			)
			(layer "B.Fab")
		)
		(fp_line
			(start -0.120396 0.2794)
			(end 0.12065 0.2794)
			(stroke
				(width 0.1)
				(type default)
			)
			(layer "B.Fab")
		)
		(fp_line
			(start 0.67945 0.3048)
			(end 0.67945 -0.305054)
			(stroke
				(width 0.1)
				(type default)
			)
			(layer "B.Fab")
		)
		(fp_line
			(start 0.12065 0.3048)
			(end 0.67945 0.3048)
			(stroke
				(width 0.1)
				(type default)
			)
			(layer "B.Fab")
		)
		(fp_line
			(start -0.120396 0.3048)
			(end -0.120396 0.2794)
			(stroke
				(width 0.1)
				(type default)
			)
			(layer "B.Fab")
		)
		(fp_line
			(start -0.67945 0.3048)
			(end -0.120396 0.3048)
			(stroke
				(width 0.1)
				(type default)
			)
			(layer "B.Fab")
		)
		(pad "1" smd circle
			(at 0.40005 0 270)
			(size 0 0)
			(layers "B.Cu" "B.Mask" "B.Paste")
			(net "GND")
		)
		(pad "2" smd circle
			(at -0.40005 0 270)
			(size 0 0)
			(layers "B.Cu" "B.Mask" "B.Paste")
			(net "BRICK2_PMBADD")
		)
	)
	(footprint ""
		(layer "B.Cu")
		(at 275.169122 -101.585522)
		(property "Reference" "PC82"
			(at 0 0 0)
			(layer "B.SilkS")
			(hide yes)
			(effects
				(font
					(size 1.27 1.27)
				)
				(justify mirror)
			)
		)
		(property "Value" ""
			(at 0 0 0)
			(layer "B.Fab")
			(effects
				(font
					(size 1.27 1.27)
				)
				(justify mirror)
			)
		)
		(duplicate_pad_numbers_are_jumpers no)
		(fp_line
			(start -1.2954 -0.5842)
			(end -1.2954 0.5842)
			(stroke
				(width 0.1524)
				(type default)
			)
			(layer "B.SilkS")
		)
		(fp_line
			(start -1.2954 0.5842)
			(end 1.2954 0.5842)
			(stroke
				(width 0.1524)
				(type default)
			)
			(layer "B.SilkS")
		)
		(fp_line
			(start 1.2954 -0.5842)
			(end -1.2954 -0.5842)
			(stroke
				(width 0.1524)
				(type default)
			)
			(layer "B.SilkS")
		)
		(fp_line
			(start 1.2954 0.5842)
			(end 1.2954 -0.5842)
			(stroke
				(width 0.1524)
				(type default)
			)
			(layer "B.SilkS")
		)
		(fp_line
			(start -1.1938 -0.4064)
			(end -1.1938 0.4064)
			(stroke
				(width 0.1)
				(type default)
			)
			(layer "B.Fab")
		)
		(fp_line
			(start -1.1938 0.4064)
			(end -0.8636 0.4064)
			(stroke
				(width 0.1)
				(type default)
			)
			(layer "B.Fab")
		)
		(fp_line
			(start -0.8636 -0.4572)
			(end -0.8636 -0.4064)
			(stroke
				(width 0.1)
				(type default)
			)
			(layer "B.Fab")
		)
		(fp_line
			(start -0.8636 -0.4064)
			(end -1.1938 -0.4064)
			(stroke
				(width 0.1)
				(type default)
			)
			(layer "B.Fab")
		)
		(fp_line
			(start -0.8636 0.4064)
			(end -0.8636 0.4572)
			(stroke
				(width 0.1)
				(type default)
			)
			(layer "B.Fab")
		)
		(fp_line
			(start -0.8636 0.4572)
			(end 0.8636 0.4572)
			(stroke
				(width 0.1)
				(type default)
			)
			(layer "B.Fab")
		)
		(fp_line
			(start 0.8636 -0.4572)
			(end -0.8636 -0.4572)
			(stroke
				(width 0.1)
				(type default)
			)
			(layer "B.Fab")
		)
		(fp_line
			(start 0.8636 -0.4064)
			(end 0.8636 -0.4572)
			(stroke
				(width 0.1)
				(type default)
			)
			(layer "B.Fab")
		)
		(fp_line
			(start 0.8636 0.4064)
			(end 1.1938 0.4064)
			(stroke
				(width 0.1)
				(type default)
			)
			(layer "B.Fab")
		)
		(fp_line
			(start 0.8636 0.4572)
			(end 0.8636 0.4064)
			(stroke
				(width 0.1)
				(type default)
			)
			(layer "B.Fab")
		)
		(fp_line
			(start 1.1938 -0.4064)
			(end 0.8636 -0.4064)
			(stroke
				(width 0.1)
				(type default)
			)
			(layer "B.Fab")
		)
		(fp_line
			(start 1.1938 0.4064)
			(end 1.1938 -0.4064)
			(stroke
				(width 0.1)
				(type default)
			)
			(layer "B.Fab")
		)
		(pad "1" smd rect
			(at 0.7366 0 270)
			(size 0.7112 0.8128)
			(layers "B.Cu" "B.Mask" "B.Paste")
			(net "P52V_HS1_4287_GATE_R")
		)
		(pad "2" smd rect
			(at -0.7366 0 270)
			(size 0.7112 0.8128)
			(layers "B.Cu" "B.Mask" "B.Paste")
			(net "P52V_HS")
		)
	)
)
